(kicad_pcb
	(version 20240108)
	(generator "pcbnew")
	(generator_version "8.0")
	(general
		(thickness 1.62)
		(legacy_teardrops no)
	)
	(paper "A4")
	(title_block
		(title "Jetson Orin Baseboard")
		(date "2025-03-12")
		(rev "1.3.4")
		(company "Antmicro Ltd")
		(comment 1 "www.antmicro.com")
		(comment 9 "footprints 609-613 of 677")
	)
	(layers
		(0 "F.Cu" signal)
		(1 "In1.Cu" signal)
		(2 "In2.Cu" signal)
		(3 "In3.Cu" signal)
		(4 "In4.Cu" jumper)
		(5 "In5.Cu" signal)
		(6 "In6.Cu" signal)
		(31 "B.Cu" signal)
		(32 "B.Adhes" user "B.Adhesive")
		(33 "F.Adhes" user "F.Adhesive")
		(34 "B.Paste" user)
		(35 "F.Paste" user)
		(36 "B.SilkS" user "B.Silkscreen")
		(37 "F.SilkS" user "F.Silkscreen")
		(38 "B.Mask" user)
		(39 "F.Mask" user)
		(40 "Dwgs.User" user "User.Drawings")
		(41 "Cmts.User" user "User.Comments")
		(42 "Eco1.User" user "User.Eco1")
		(43 "Eco2.User" user "User.Eco2")
		(44 "Edge.Cuts" user)
		(45 "Margin" user)
		(46 "B.CrtYd" user "B.Courtyard")
		(47 "F.CrtYd" user "F.Courtyard")
		(48 "B.Fab" user)
		(49 "F.Fab" user)
	)
	(footprint "antmicro-footprints:R_0402_1005Metric"
		(layer "B.Cu")
		(at 59.34 74.9)
		(descr "Resistor SMD 0402")
		(tags "resistor SMD 0402")
		(property "Reference" "R249"
			(at 22.91 9.23 180)
			(layer "B.SilkS")
			(effects
				(font
					(size 0.7 0.7)
					(thickness 0.15)
				)
				(justify left bottom mirror)
			)
		)
		(property "Value" "R_100k_0402"
			(at 0 -1.4 180)
			(layer "B.Fab")
			(effects
				(font
					(size 0.7 0.7)
					(thickness 0.15)
				)
				(justify left bottom mirror)
			)
		)
		(property "Footprint" "antmicro-footprints:R_0402_1005Metric"
			(at 0 0 0)
			(layer "F.Fab")
			(hide yes)
			(effects
				(font
					(size 1.27 1.27)
					(thickness 0.15)
				)
			)
		)
		(property "Datasheet" "https://www.bourns.com/docs/product-datasheets/cr.pdf"
			(at 0 0 0)
			(layer "F.Fab")
			(hide yes)
			(effects
				(font
					(size 1.27 1.27)
					(thickness 0.15)
				)
			)
		)
		(property "Author" "Antmicro"
			(at 0 0 0)
			(layer "B.Fab")
			(hide yes)
			(effects
				(font
					(size 1 1)
					(thickness 0.15)
				)
				(justify mirror)
			)
		)
		(property "License" "Apache-2.0"
			(at 0 0 0)
			(layer "B.Fab")
			(hide yes)
			(effects
				(font
					(size 1 1)
					(thickness 0.15)
				)
				(justify mirror)
			)
		)
		(property "MPN" "CR0402-FX-1003GLF"
			(at 0 0 0)
			(layer "B.Fab")
			(hide yes)
			(effects
				(font
					(size 1 1)
					(thickness 0.15)
				)
				(justify mirror)
			)
		)
		(property "Manufacturer" "Bourns"
			(at 0 0 0)
			(layer "B.Fab")
			(hide yes)
			(effects
				(font
					(size 1 1)
					(thickness 0.15)
				)
				(justify mirror)
			)
		)
		(property "Tolerance" "1%"
			(at 0 0 0)
			(layer "B.Fab")
			(hide yes)
			(effects
				(font
					(size 1 1)
					(thickness 0.15)
				)
				(justify mirror)
			)
		)
		(property "Val" "100k"
			(at 0 0 0)
			(layer "B.Fab")
			(hide yes)
			(effects
				(font
					(size 1 1)
					(thickness 0.15)
				)
				(justify mirror)
			)
		)
		(sheetname "Supply")
		(sheetfile "supply.kicad_sch")
		(attr smd)
		(fp_rect
			(start -0.925 0.47)
			(end 0.925 -0.47)
			(stroke
				(width 0.05)
				(type default)
			)
			(fill none)
			(layer "B.CrtYd")
		)
		(fp_rect
			(start -0.5 0.25)
			(end 0.5 -0.25)
			(stroke
				(width 0.15)
				(type solid)
			)
			(fill none)
			(layer "B.Fab")
		)
		(fp_text user "License: Apache-2.0"
			(at -0.95 -5.169 180)
			(layer "B.Fab")
			(hide yes)
			(effects
				(font
					(size 0.7 0.7)
					(thickness 0.15)
				)
				(justify left bottom mirror)
			)
		)
		(fp_text user "Author: Antmicro"
			(at -0.95 -4.169 180)
			(layer "B.Fab")
			(hide yes)
			(effects
				(font
					(size 0.7 0.7)
					(thickness 0.15)
				)
				(justify left bottom mirror)
			)
		)
		(fp_text user "${REFERENCE}"
			(at -0.95 -3.168 180)
			(layer "B.Fab")
			(hide yes)
			(effects
				(font
					(size 0.7 0.7)
					(thickness 0.15)
				)
				(justify left bottom mirror)
			)
		)
		(pad "1" smd roundrect
			(at -0.48 0)
			(size 0.59 0.64)
			(layers "B.Cu" "B.Paste" "B.Mask")
			(roundrect_rratio 0.25)
			(net 1 "GND")
			(pintype "passive")
		)
		(pad "2" smd roundrect
			(at 0.48 0)
			(size 0.59 0.64)
			(layers "B.Cu" "B.Paste" "B.Mask")
			(roundrect_rratio 0.25)
			(net 279 "PWR_SOFT")
			(pintype "passive")
		)
	)
	(footprint "antmicro-footprints:C_0603_1608Metric"
		(layer "B.Cu")
		(at 114.5 93 180)
		(descr "Capacitor SMD 0603")
		(tags "capacitor 0603")
		(property "Reference" "C23"
			(at -1.05 -1.4 0)
			(layer "B.SilkS")
			(effects
				(font
					(size 0.7 0.7)
					(thickness 0.15)
				)
				(justify left bottom mirror)
			)
		)
		(property "Value" "C_10u_0603"
			(at 0 -1.6 0)
			(layer "B.Fab")
			(effects
				(font
					(size 0.7 0.7)
					(thickness 0.15)
				)
				(justify left bottom mirror)
			)
		)
		(property "Footprint" "antmicro-footprints:C_0603_1608Metric"
			(at 0 0 180)
			(layer "F.Fab")
			(hide yes)
			(effects
				(font
					(size 1.27 1.27)
					(thickness 0.15)
				)
			)
		)
		(property "Datasheet" "https://www.murata.com/products/productdetail?partno=GRM188R61A106KE69%23"
			(at 0 0 180)
			(layer "F.Fab")
			(hide yes)
			(effects
				(font
					(size 1.27 1.27)
					(thickness 0.15)
				)
			)
		)
		(property "Author" "Antmicro"
			(at 229 186 0)
			(layer "B.Fab")
			(hide yes)
			(effects
				(font
					(size 1 1)
					(thickness 0.15)
				)
				(justify mirror)
			)
		)
		(property "Dielectric" "template_dielectric"
			(at 229 186 0)
			(layer "B.Fab")
			(hide yes)
			(effects
				(font
					(size 1 1)
					(thickness 0.15)
				)
				(justify mirror)
			)
		)
		(property "License" "Apache-2.0"
			(at 229 186 0)
			(layer "B.Fab")
			(hide yes)
			(effects
				(font
					(size 1 1)
					(thickness 0.15)
				)
				(justify mirror)
			)
		)
		(property "MPN" "GRM188R61A106KE69D"
			(at 229 186 0)
			(layer "B.Fab")
			(hide yes)
			(effects
				(font
					(size 1 1)
					(thickness 0.15)
				)
				(justify mirror)
			)
		)
		(property "Manufacturer" "Murata"
			(at 229 186 0)
			(layer "B.Fab")
			(hide yes)
			(effects
				(font
					(size 1 1)
					(thickness 0.15)
				)
				(justify mirror)
			)
		)
		(property "Val" "10u"
			(at 229 186 0)
			(layer "B.Fab")
			(hide yes)
			(effects
				(font
					(size 1 1)
					(thickness 0.15)
				)
				(justify mirror)
			)
		)
		(property "Voltage" ""
			(at 229 186 0)
			(layer "B.Fab")
			(hide yes)
			(effects
				(font
					(size 1 1)
					(thickness 0.15)
				)
				(justify mirror)
			)
		)
		(sheetname "M.2")
		(sheetfile "m-2.kicad_sch")
		(attr smd)
		(fp_line
			(start 0.15 0.4)
			(end -0.15 0.4)
			(stroke
				(width 0.15)
				(type solid)
			)
			(layer "B.SilkS")
		)
		(fp_line
			(start 0.15 -0.4)
			(end -0.15 -0.4)
			(stroke
				(width 0.15)
				(type solid)
			)
			(layer "B.SilkS")
		)
		(fp_rect
			(start -1.25 0.65)
			(end 1.25 -0.65)
			(stroke
				(width 0.05)
				(type solid)
			)
			(fill none)
			(layer "B.CrtYd")
		)
		(fp_rect
			(start -0.8 0.4)
			(end 0.8 -0.4)
			(stroke
				(width 0.15)
				(type solid)
			)
			(fill none)
			(layer "B.Fab")
		)
		(fp_text user "Author: Antmicro"
			(at -1.682 -4.894 0)
			(layer "B.Fab")
			(hide yes)
			(effects
				(font
					(size 0.7 0.7)
					(thickness 0.15)
				)
				(justify left bottom mirror)
			)
		)
		(fp_text user "${REFERENCE}"
			(at -1.682 -3.895 0)
			(layer "B.Fab")
			(hide yes)
			(effects
				(font
					(size 0.7 0.7)
					(thickness 0.15)
				)
				(justify left bottom mirror)
			)
		)
		(fp_text user "License: Apache-2.0"
			(at -1.682 -5.895 0)
			(layer "B.Fab")
			(hide yes)
			(effects
				(font
					(size 0.7 0.7)
					(thickness 0.15)
				)
				(justify left bottom mirror)
			)
		)
		(pad "1" smd roundrect
			(at -0.7 0 180)
			(size 0.8 1)
			(layers "B.Cu" "B.Paste" "B.Mask")
			(roundrect_rratio 0.2)
			(net 635 "/M.2/3V3_M2")
			(pintype "passive")
		)
		(pad "2" smd roundrect
			(at 0.7 0 180)
			(size 0.8 1)
			(layers "B.Cu" "B.Paste" "B.Mask")
			(roundrect_rratio 0.2)
			(net 1 "GND")
			(pintype "passive")
		)
	)
	(footprint "antmicro-footprints:R_0402_1005Metric"
		(layer "B.Cu")
		(at 56.3 76.2)
		(descr "Resistor SMD 0402")
		(tags "resistor SMD 0402")
		(property "Reference" "R257"
			(at 20.08 9.2 0)
			(layer "B.SilkS")
			(effects
				(font
					(size 0.7 0.7)
					(thickness 0.15)
				)
				(justify right bottom mirror)
			)
		)
		(property "Value" "R_200k_0402"
			(at 0 -1.4 0)
			(layer "B.Fab")
			(effects
				(font
					(size 0.7 0.7)
					(thickness 0.15)
				)
				(justify right bottom mirror)
			)
		)
		(property "Footprint" "antmicro-footprints:R_0402_1005Metric"
			(at 0 0 0)
			(layer "F.Fab")
			(hide yes)
			(effects
				(font
					(size 1.27 1.27)
					(thickness 0.15)
				)
			)
		)
		(property "Datasheet" "https://www.bourns.com/docs/product-datasheets/cr.pdf"
			(at 0 0 0)
			(layer "F.Fab")
			(hide yes)
			(effects
				(font
					(size 1.27 1.27)
					(thickness 0.15)
				)
			)
		)
		(property "Author" "Antmicro"
			(at 0 0 0)
			(layer "B.Fab")
			(hide yes)
			(effects
				(font
					(size 1 1)
					(thickness 0.15)
				)
				(justify mirror)
			)
		)
		(property "License" "Apache-2.0"
			(at 0 0 0)
			(layer "B.Fab")
			(hide yes)
			(effects
				(font
					(size 1 1)
					(thickness 0.15)
				)
				(justify mirror)
			)
		)
		(property "MPN" "CR0402-FX-2003GLF"
			(at 0 0 0)
			(layer "B.Fab")
			(hide yes)
			(effects
				(font
					(size 1 1)
					(thickness 0.15)
				)
				(justify mirror)
			)
		)
		(property "Manufacturer" "Bourns"
			(at 0 0 0)
			(layer "B.Fab")
			(hide yes)
			(effects
				(font
					(size 1 1)
					(thickness 0.15)
				)
				(justify mirror)
			)
		)
		(property "Tolerance" "1%"
			(at 0 0 0)
			(layer "B.Fab")
			(hide yes)
			(effects
				(font
					(size 1 1)
					(thickness 0.15)
				)
				(justify mirror)
			)
		)
		(property "Val" "200k"
			(at 0 0 0)
			(layer "B.Fab")
			(hide yes)
			(effects
				(font
					(size 1 1)
					(thickness 0.15)
				)
				(justify mirror)
			)
		)
		(sheetname "Supply")
		(sheetfile "supply.kicad_sch")
		(attr smd)
		(fp_rect
			(start -0.925 0.47)
			(end 0.925 -0.47)
			(stroke
				(width 0.05)
				(type default)
			)
			(fill none)
			(layer "B.CrtYd")
		)
		(fp_rect
			(start -0.5 0.25)
			(end 0.5 -0.25)
			(stroke
				(width 0.15)
				(type solid)
			)
			(fill none)
			(layer "B.Fab")
		)
		(fp_text user "${REFERENCE}"
			(at -0.95 -3.168 0)
			(layer "B.Fab")
			(hide yes)
			(effects
				(font
					(size 0.7 0.7)
					(thickness 0.15)
				)
				(justify right bottom mirror)
			)
		)
		(fp_text user "Author: Antmicro"
			(at -0.95 -4.169 0)
			(layer "B.Fab")
			(hide yes)
			(effects
				(font
					(size 0.7 0.7)
					(thickness 0.15)
				)
				(justify right bottom mirror)
			)
		)
		(fp_text user "License: Apache-2.0"
			(at -0.95 -5.169 0)
			(layer "B.Fab")
			(hide yes)
			(effects
				(font
					(size 0.7 0.7)
					(thickness 0.15)
				)
				(justify right bottom mirror)
			)
		)
		(pad "1" smd roundrect
			(at -0.48 0)
			(size 0.59 0.64)
			(layers "B.Cu" "B.Paste" "B.Mask")
			(roundrect_rratio 0.25)
			(net 530 "Net-(R256-Pad1)")
			(pintype "passive")
		)
		(pad "2" smd roundrect
			(at 0.48 0)
			(size 0.59 0.64)
			(layers "B.Cu" "B.Paste" "B.Mask")
			(roundrect_rratio 0.25)
			(net 174 "Net-(D36-C)")
			(pintype "passive")
		)
	)
	(footprint "antmicro-footprints:SOD-923"
		(layer "B.Cu")
		(at 115.4175 117.825)
		(property "Reference" "D10"
			(at 1.1325 -0.575 0)
			(unlocked yes)
			(layer "B.SilkS")
			(effects
				(font
					(size 0.7 0.7)
					(thickness 0.15)
				)
				(justify left bottom mirror)
			)
		)
		(property "Value" "ESD9X5.0ST5G"
			(at 0 -1.3 180)
			(unlocked yes)
			(layer "B.Fab")
			(effects
				(font
					(size 0.7 0.7)
					(thickness 0.15)
				)
				(justify left bottom mirror)
			)
		)
		(property "Footprint" "antmicro-footprints:SOD-923"
			(at 0 0 0)
			(layer "F.Fab")
			(hide yes)
			(effects
				(font
					(size 1.27 1.27)
					(thickness 0.15)
				)
			)
		)
		(property "Datasheet" "https://www.onsemi.com/pdf/datasheet/esd9x3.3st5g-d.pdf"
			(at 0 0 0)
			(layer "F.Fab")
			(hide yes)
			(effects
				(font
					(size 1.27 1.27)
					(thickness 0.15)
				)
			)
		)
		(property "Author" "Antmicro"
			(at 0 0 0)
			(layer "B.Fab")
			(hide yes)
			(effects
				(font
					(size 1 1)
					(thickness 0.15)
				)
				(justify mirror)
			)
		)
		(property "License" "Apache-2.0"
			(at 0 0 0)
			(layer "B.Fab")
			(hide yes)
			(effects
				(font
					(size 1 1)
					(thickness 0.15)
				)
				(justify mirror)
			)
		)
		(property "MPN" "ESD9X5.0ST5G"
			(at 0 0 0)
			(layer "B.Fab")
			(hide yes)
			(effects
				(font
					(size 1 1)
					(thickness 0.15)
				)
				(justify mirror)
			)
		)
		(property "Manufacturer" "ON Semiconductor"
			(at 0 0 0)
			(layer "B.Fab")
			(hide yes)
			(effects
				(font
					(size 1 1)
					(thickness 0.15)
				)
				(justify mirror)
			)
		)
		(sheetname "USB3")
		(sheetfile "usb3.kicad_sch")
		(attr smd)
		(fp_line
			(start -0.5 -0.3)
			(end -0.5 -0.4)
			(stroke
				(width 0.15)
				(type solid)
			)
			(layer "B.SilkS")
		)
		(fp_line
			(start -0.5 0.4)
			(end -0.5 0.3)
			(stroke
				(width 0.15)
				(type solid)
			)
			(layer "B.SilkS")
		)
		(fp_line
			(start -0.16 -0.4)
			(end -0.16 0.4)
			(stroke
				(width 0.15)
				(type solid)
			)
			(layer "B.SilkS")
		)
		(fp_line
			(start 0.5 -0.4)
			(end -0.5 -0.4)
			(stroke
				(width 0.15)
				(type solid)
			)
			(layer "B.SilkS")
		)
		(fp_line
			(start 0.5 -0.3)
			(end 0.5 -0.4)
			(stroke
				(width 0.15)
				(type solid)
			)
			(layer "B.SilkS")
		)
		(fp_line
			(start 0.5 0.3)
			(end 0.5 0.4)
			(stroke
				(width 0.15)
				(type solid)
			)
			(layer "B.SilkS")
		)
		(fp_line
			(start 0.5 0.4)
			(end -0.5 0.4)
			(stroke
				(width 0.15)
				(type solid)
			)
			(layer "B.SilkS")
		)
		(fp_rect
			(start -0.68 0.41)
			(end 0.68 -0.41)
			(stroke
				(width 0.05)
				(type solid)
			)
			(fill none)
			(layer "B.CrtYd")
		)
		(fp_line
			(start -0.202 -0.298)
			(end -0.202 0.3)
			(stroke
				(width 0.15)
				(type solid)
			)
			(layer "B.Fab")
		)
		(fp_rect
			(start -0.402 0.3)
			(end 0.4 -0.298)
			(stroke
				(width 0.15)
				(type solid)
			)
			(fill none)
			(layer "B.Fab")
		)
		(fp_text user "License: Apache-2.0"
			(at -0.68 -4.5 180)
			(layer "B.Fab")
			(hide yes)
			(effects
				(font
					(size 0.7 0.7)
					(thickness 0.15)
				)
				(justify left bottom mirror)
			)
		)
		(fp_text user "Author: Antmicro"
			(at -0.68 -5.7 180)
			(layer "B.Fab")
			(hide yes)
			(effects
				(font
					(size 0.7 0.7)
					(thickness 0.15)
				)
				(justify left bottom mirror)
			)
		)
		(fp_text user "${REFERENCE}"
			(at -0.68 -3.3 180)
			(unlocked yes)
			(layer "B.Fab")
			(hide yes)
			(effects
				(font
					(size 0.7 0.7)
					(thickness 0.15)
				)
				(justify left bottom mirror)
			)
		)
		(pad "1" smd roundrect
			(at -0.438 0)
			(size 0.4 0.325)
			(layers "B.Cu" "B.Paste" "B.Mask")
			(roundrect_rratio 0.25)
			(net 270 "/USB3/USBC1_VBUS")
			(pinfunction "C")
			(pintype "passive")
		)
		(pad "2" smd roundrect
			(at 0.436 0)
			(size 0.4 0.325)
			(layers "B.Cu" "B.Paste" "B.Mask")
			(roundrect_rratio 0.25)
			(net 1 "GND")
			(pinfunction "A")
			(pintype "passive")
		)
	)
	(footprint "antmicro-footprints:R_0603_1608Metric"
		(layer "B.Cu")
		(at 49.59 77.66)
		(descr "Resistor SMD 0603")
		(tags "resistor SMD 0603")
		(property "Reference" "R175"
			(at 1.41 -0.535 180)
			(layer "B.SilkS")
			(effects
				(font
					(size 0.7 0.7)
					(thickness 0.15)
				)
				(justify left bottom mirror)
			)
		)
		(property "Value" "R_0R_22.4A_0603"
			(at 0 -1.6 180)
			(layer "B.Fab")
			(effects
				(font
					(size 0.7 0.7)
					(thickness 0.15)
				)
				(justify left bottom mirror)
			)
		)
		(property "Footprint" "antmicro-footprints:R_0603_1608Metric"
			(at 0 0 0)
			(layer "F.Fab")
			(hide yes)
			(effects
				(font
					(size 1.27 1.27)
					(thickness 0.15)
				)
			)
		)
		(property "Datasheet" "https://fscdn.rohm.com/en/products/databook/datasheet/passive/resistor/chip_resistor/pmr-jpw-e.pdf"
			(at 0 0 0)
			(layer "F.Fab")
			(hide yes)
			(effects
				(font
					(size 1.27 1.27)
					(thickness 0.15)
				)
			)
		)
		(property "Author" "Antmicro"
			(at 0 0 0)
			(layer "B.Fab")
			(hide yes)
			(effects
				(font
					(size 1 1)
					(thickness 0.15)
				)
				(justify mirror)
			)
		)
		(property "License" "Apache-2.0"
			(at 0 0 0)
			(layer "B.Fab")
			(hide yes)
			(effects
				(font
					(size 1 1)
					(thickness 0.15)
				)
				(justify mirror)
			)
		)
		(property "MPN" "PMR03EZPJ000"
			(at 0 0 0)
			(layer "B.Fab")
			(hide yes)
			(effects
				(font
					(size 1 1)
					(thickness 0.15)
				)
				(justify mirror)
			)
		)
		(property "Manufacturer" "ROHM Semiconductor"
			(at 0 0 0)
			(layer "B.Fab")
			(hide yes)
			(effects
				(font
					(size 1 1)
					(thickness 0.15)
				)
				(justify mirror)
			)
		)
		(property "Max. Curr." "22.4A"
			(at 0 0 0)
			(layer "B.Fab")
			(hide yes)
			(effects
				(font
					(size 1 1)
					(thickness 0.15)
				)
				(justify mirror)
			)
		)
		(property "Tolerance" "template_tolerance"
			(at 0 0 0)
			(layer "B.Fab")
			(hide yes)
			(effects
				(font
					(size 1 1)
					(thickness 0.15)
				)
				(justify mirror)
			)
		)
		(property "Val" "0R"
			(at 0 0 0)
			(layer "B.Fab")
			(hide yes)
			(effects
				(font
					(size 1 1)
					(thickness 0.15)
				)
				(justify mirror)
			)
		)
		(sheetname "Supply")
		(sheetfile "supply.kicad_sch")
		(attr smd exclude_from_pos_files exclude_from_bom dnp)
		(fp_line
			(start 0.15 -0.4)
			(end -0.15 -0.4)
			(stroke
				(width 0.15)
				(type solid)
			)
			(layer "B.SilkS")
		)
		(fp_line
			(start 0.15 0.4)
			(end -0.15 0.4)
			(stroke
				(width 0.15)
				(type solid)
			)
			(layer "B.SilkS")
		)
		(fp_rect
			(start -1.25 0.65)
			(end 1.25 -0.65)
			(stroke
				(width 0.05)
				(type solid)
			)
			(fill none)
			(layer "B.CrtYd")
		)
		(fp_rect
			(start -0.8 0.4)
			(end 0.8 -0.4)
			(stroke
				(width 0.15)
				(type solid)
			)
			(fill none)
			(layer "B.Fab")
		)
		(fp_text user "License: Apache-2.0"
			(at -1.25 -5.9 180)
			(layer "B.Fab")
			(hide yes)
			(effects
				(font
					(size 0.7 0.7)
					(thickness 0.15)
				)
				(justify left bottom mirror)
			)
		)
		(fp_text user "Author: Antmicro"
			(at -1.25 -4.9 180)
			(layer "B.Fab")
			(hide yes)
			(effects
				(font
					(size 0.7 0.7)
					(thickness 0.15)
				)
				(justify left bottom mirror)
			)
		)
		(fp_text user "${REFERENCE}"
			(at -1.25 -3.898 180)
			(layer "B.Fab")
			(hide yes)
			(effects
				(font
					(size 0.7 0.7)
					(thickness 0.15)
				)
				(justify left bottom mirror)
			)
		)
		(pad "1" smd roundrect
			(at -0.7 0)
			(size 0.8 1)
			(layers "B.Cu" "B.Paste" "B.Mask")
			(roundrect_rratio 0.2)
			(net 328 "/Supply/VCC_IN")
			(pintype "passive")
		)
		(pad "2" smd roundrect
			(at 0.7 0)
			(size 0.8 1)
			(layers "B.Cu" "B.Paste" "B.Mask")
			(roundrect_rratio 0.2)
			(net 115 "VCC")
			(pintype "passive")
		)
	)
)
